FILE_TYPE = MACRO_DRAWING;
SET COLOR_WIRE YELLOW;
SET COLOR_PROP ORANGE;
SET COLOR_DOT WHITE;
SET COLOR_ARC YELLOW;
SET COLOR_BODY GREEN;
SET COLOR_NOTE PURPLE;
SET PROP_DISPLAY VALUE;
SET PAGE_NUMBER P410;
FORCEADD OFFPAGE..3
R 2
(-6375 5500);
FORCEPROP 2 LAST $XR1 186 
J 0
(-6805 5500);
DISPLAY 0.638298 (-6805 5500);
PAINT MONO (-6805 5500);
FORCEPROP 2 LAST $XR0 185 
J 0
(-6685 5500);
DISPLAY 0.638298 (-6685 5500);
PAINT MONO (-6685 5500);
FORCEPROP 2 LAST CDS_LIB standard
J 0
(-6375 5500);
DISPLAY INVISIBLE (-6375 5500);
FORCEPROP 1 LAST OFFPAGE TRUE
J 2
(-6700 5375);
DISPLAY 0.872340 (-6700 5375);
PAINT GREEN (-6700 5375);
DISPLAY INVISIBLE (-6700 5375);
FORCEPROP 1 LAST COMMENT_BODY TRUE
J 2
(-6325 5400);
DISPLAY 0.872340 (-6325 5400);
PAINT GREEN (-6325 5400);
DISPLAY INVISIBLE (-6325 5400);
FORCEPROP 2 LAST PATH I1
J 0
(-6325 5575);
DISPLAY 0.680851 (-6325 5575);
DISPLAY INVISIBLE (-6325 5575);
FORCEADD OFFPAGE..1
(-6400 5550);
FORCEPROP 2 LAST $XR1 186 
J 0
(-6772 5550);
DISPLAY 0.638298 (-6772 5550);
PAINT MONO (-6772 5550);
FORCEPROP 2 LAST $XR0 185 
J 0
(-6652 5550);
DISPLAY 0.638298 (-6652 5550);
PAINT MONO (-6652 5550);
FORCEPROP 2 LAST CDS_LIB standard
J 0
(-6400 5550);
DISPLAY INVISIBLE (-6400 5550);
FORCEPROP 1 LAST OFFPAGE TRUE
J 0
(-6075 5425);
DISPLAY 0.872340 (-6075 5425);
DISPLAY INVISIBLE (-6075 5425);
FORCEPROP 1 LAST COMMENT_BODY TRUE
J 0
(-6275 5450);
DISPLAY 0.872340 (-6275 5450);
PAINT GREEN (-6275 5450);
DISPLAY INVISIBLE (-6275 5450);
FORCEPROP 2 LAST PATH I2
J 0
(-6350 5625);
DISPLAY 0.680851 (-6350 5625);
DISPLAY INVISIBLE (-6350 5625);
FORCEADD Q_RES..2
(-3075 5375);
FORCEPROP 1 LAST LOCATION R1044
J 0
(-3030 5500);
DISPLAY 0.978723 (-3030 5500);
FORCEPROP 0 LAST $SEC 1
J 0
(-3025 5550);
DISPLAY 0.680851 (-3025 5550);
PAINT MONO (-3025 5550);
DISPLAY INVISIBLE (-3025 5550);
FORCEPROP 0 LAST CDS_SEC 1
J 0
(-3025 5550);
DISPLAY 0.680851 (-3025 5550);
DISPLAY INVISIBLE (-3025 5550);
FORCEPROP 1 LASTPIN (-3075 5475) $PN 1
J 0
(-3070 5437);
DISPLAY 0.787234 (-3070 5437);
PAINT MONO (-3070 5437);
FORCEPROP 1 LASTPIN (-3075 5275) $PN 2
J 0
(-3070 5285);
DISPLAY 0.787234 (-3070 5285);
PAINT MONO (-3070 5285);
FORCEPROP 1 LAST WATTAGE 1/20W
J 0
(-3035 5350);
DISPLAY 0.978723 (-3035 5350);
FORCEPROP 1 LAST TOLERANCE 1%
J 0
(-3030 5400);
DISPLAY 0.978723 (-3030 5400);
FORCEPROP 1 LAST MATERIAL CHIP
J 0
(-3035 5300);
DISPLAY 0.978723 (-3035 5300);
FORCEPROP 1 LAST VALUE 1K
J 0
(-3030 5450);
DISPLAY 0.978723 (-3030 5450);
FORCEPROP 1 LAST PACK_TYPE 0201LF
J 0
(-3035 5200);
DISPLAY 0.978723 (-3035 5200);
FORCEPROP 2 LAST CDS_LIB pure_quanta
J 0
(-3075 5375);
DISPLAY INVISIBLE (-3075 5375);
FORCEPROP 1 LAST PATH I20
J 0
(-3025 5550);
DISPLAY 0.978723 (-3025 5550);
PAINT WHITE (-3025 5550);
DISPLAY INVISIBLE (-3025 5550);
FORCEPROP 1 LAST PART_NUMBER CS21001FE07
J 0
(-3035 5250);
DISPLAY 0.978723 (-3035 5250);
DISPLAY INVISIBLE (-3035 5250);
FORCEADD UNIVERSAL_GND..1
(-3225 5300);
FORCEPROP 3 LASTPIN (-3225 5350) SIG_NAME GND\g
J 0
(-3215 5360);
DISPLAY 0.659574 (-3215 5360);
PAINT MONO (-3215 5360);
DISPLAY INVISIBLE (-3215 5360);
FORCEPROP 2 LAST CDS_LIB pure_quanta_power
J 0
(-3225 5300);
DISPLAY INVISIBLE (-3225 5300);
FORCEPROP 1 LAST HDL_POWER GND
J 1
(-3200 5225);
DISPLAY 0.872340 (-3200 5225);
PAINT GREEN (-3200 5225);
DISPLAY INVISIBLE (-3200 5225);
FORCEPROP 1 LAST PATH I21
J 0
(-3150 5300);
DISPLAY 0.872340 (-3150 5300);
PAINT AQUA (-3150 5300);
DISPLAY INVISIBLE (-3150 5300);
FORCEADD UNIVERSAL_GND..1
(-3075 4950);
FORCEPROP 3 LASTPIN (-3075 5000) SIG_NAME GND\g
J 0
(-3065 5010);
DISPLAY 0.659574 (-3065 5010);
PAINT MONO (-3065 5010);
DISPLAY INVISIBLE (-3065 5010);
FORCEPROP 2 LAST CDS_LIB pure_quanta_power
J 0
(-3075 4950);
DISPLAY INVISIBLE (-3075 4950);
FORCEPROP 1 LAST HDL_POWER GND
J 1
(-3050 4875);
DISPLAY 0.872340 (-3050 4875);
PAINT GREEN (-3050 4875);
DISPLAY INVISIBLE (-3050 4875);
FORCEPROP 1 LAST PATH I22
J 0
(-3000 4950);
DISPLAY 0.872340 (-3000 4950);
PAINT AQUA (-3000 4950);
DISPLAY INVISIBLE (-3000 4950);
FORCEADD P1V0..1
(-4200 6425);
FORCEPROP 3 LASTPIN (-4200 6375) SIG_NAME P1V8_CPU0_RT_1D\g
J 0
(-4190 6385);
DISPLAY 0.659574 (-4190 6385);
PAINT MONO (-4190 6385);
DISPLAY INVISIBLE (-4190 6385);
FORCEPROP 1 LAST HDL_POWER P1V8_CPU0_RT_1D
J 1
(-4200 6475);
DISPLAY 0.489362 (-4200 6475);
PAINT SKYBLUE (-4200 6475);
FORCEPROP 2 LAST CDS_LIB pure_quanta_power
J 0
(-4200 6425);
DISPLAY INVISIBLE (-4200 6425);
FORCEPROP 1 LAST PATH I23
J 0
(-4150 6450);
DISPLAY 0.872340 (-4150 6450);
PAINT AQUA (-4150 6450);
DISPLAY INVISIBLE (-4150 6450);
FORCEADD Q_CAP..1
(-4500 6075);
FORCEPROP 1 LAST LOCATION C664
J 0
(-4450 6175);
DISPLAY 0.787234 (-4450 6175);
PAINT SKYBLUE (-4450 6175);
FORCEPROP 0 LAST $SEC 1
J 0
(-4450 6225);
DISPLAY 0.680851 (-4450 6225);
PAINT MONO (-4450 6225);
DISPLAY INVISIBLE (-4450 6225);
FORCEPROP 0 LAST CDS_SEC 1
J 0
(-4450 6225);
DISPLAY 0.680851 (-4450 6225);
DISPLAY INVISIBLE (-4450 6225);
FORCEPROP 1 LASTPIN (-4500 6175) $PN 1
J 0
(-4490 6155);
DISPLAY 0.787234 (-4490 6155);
PAINT MONO (-4490 6155);
FORCEPROP 1 LASTPIN (-4500 5975) $PN 2
J 0
(-4490 5955);
DISPLAY 0.787234 (-4490 5955);
PAINT MONO (-4490 5955);
FORCEPROP 1 LAST VALUE 0.1UF
J 0
(-4450 6125);
DISPLAY 0.510638 (-4450 6125);
FORCEPROP 1 LAST VOLTAGE 10V
J 0
(-4450 6075);
DISPLAY 0.510638 (-4450 6075);
FORCEPROP 1 LAST TOLERANCE 10%
J 0
(-4450 6025);
DISPLAY 0.510638 (-4450 6025);
FORCEPROP 1 LAST MATERIAL X7S
J 0
(-4450 5975);
DISPLAY 0.510638 (-4450 5975);
FORCEPROP 1 LAST PACK_TYPE C0201
J 0
(-4450 5925);
DISPLAY 0.510638 (-4450 5925);
FORCEPROP 2 LAST CDS_LIB pure_quanta
J 0
(-4500 6075);
DISPLAY INVISIBLE (-4500 6075);
FORCEPROP 1 LAST PATH I24
J 0
(-4450 6225);
DISPLAY 0.978723 (-4450 6225);
PAINT WHITE (-4450 6225);
DISPLAY INVISIBLE (-4450 6225);
FORCEPROP 1 LAST PART_NUMBER CH4102K6E00
J 0
(-4450 5925);
DISPLAY 0.978723 (-4450 5925);
DISPLAY INVISIBLE (-4450 5925);
FORCEADD UNIVERSAL_GND..1
(-4500 5800);
FORCEPROP 3 LASTPIN (-4500 5850) SIG_NAME GND\g
J 0
(-4490 5860);
DISPLAY 0.659574 (-4490 5860);
PAINT MONO (-4490 5860);
DISPLAY INVISIBLE (-4490 5860);
FORCEPROP 2 LAST CDS_LIB pure_quanta_power
J 0
(-4500 5800);
DISPLAY INVISIBLE (-4500 5800);
FORCEPROP 1 LAST HDL_POWER GND
J 1
(-4475 5725);
DISPLAY 0.872340 (-4475 5725);
PAINT GREEN (-4475 5725);
DISPLAY INVISIBLE (-4475 5725);
FORCEPROP 1 LAST PATH I25
J 0
(-4425 5800);
DISPLAY 0.872340 (-4425 5800);
PAINT AQUA (-4425 5800);
DISPLAY INVISIBLE (-4425 5800);
FORCEADD UNIVERSAL_GND..1
R 7
(-4225 5600);
FORCEPROP 3 LASTPIN (-4175 5600) SIG_NAME GND\g
J 0
(-4165 5610);
DISPLAY 0.659574 (-4165 5610);
PAINT MONO (-4165 5610);
DISPLAY INVISIBLE (-4165 5610);
FORCEPROP 2 LAST CDS_LIB pure_quanta_power
J 0
(-4225 5600);
DISPLAY INVISIBLE (-4225 5600);
FORCEPROP 1 LAST HDL_POWER GND
R 1
J 1
(-4300 5625);
DISPLAY 0.872340 (-4300 5625);
PAINT GREEN (-4300 5625);
DISPLAY INVISIBLE (-4300 5625);
FORCEPROP 1 LAST PATH I26
R 1
J 0
(-4225 5675);
DISPLAY 0.872340 (-4225 5675);
PAINT AQUA (-4225 5675);
DISPLAY INVISIBLE (-4225 5675);
FORCEADD M24M02DRMN6TP..1
(-3750 5575);
FORCEPROP 1 LAST LOCATION U15
J 0
(-3944 5915);
DISPLAY 0.723404 (-3944 5915);
PAINT GREEN (-3944 5915);
FORCEPROP 0 LAST $SEC 1
J 0
(-3925 6050);
DISPLAY 0.680851 (-3925 6050);
PAINT MONO (-3925 6050);
DISPLAY INVISIBLE (-3925 6050);
FORCEPROP 0 LAST CDS_SEC 1
J 0
(-3925 6050);
DISPLAY 0.680851 (-3925 6050);
DISPLAY INVISIBLE (-3925 6050);
FORCEPROP 0 LASTPIN (-3425 5650) $PN 1
J 0
(-3415 5660);
DISPLAY 0.680851 (-3415 5660);
PAINT MONO (-3415 5660);
FORCEPROP 0 LASTPIN (-3425 5600) $PN 2
J 0
(-3415 5610);
DISPLAY 0.680851 (-3415 5610);
PAINT MONO (-3415 5610);
FORCEPROP 0 LASTPIN (-3425 5550) $PN 3
J 0
(-3415 5560);
DISPLAY 0.680851 (-3415 5560);
PAINT MONO (-3415 5560);
FORCEPROP 0 LASTPIN (-4075 5550) $PN 6
J 2
(-4085 5560);
DISPLAY 0.680851 (-4085 5560);
PAINT MONO (-4085 5560);
FORCEPROP 0 LASTPIN (-4075 5500) $PN 5
J 2
(-4085 5510);
DISPLAY 0.680851 (-4085 5510);
PAINT MONO (-4085 5510);
FORCEPROP 0 LASTPIN (-4075 5650) $PN 8
J 2
(-4085 5660);
DISPLAY 0.680851 (-4085 5660);
PAINT MONO (-4085 5660);
FORCEPROP 0 LASTPIN (-3425 5500) $PN 4
J 0
(-3415 5510);
DISPLAY 0.680851 (-3415 5510);
PAINT MONO (-3415 5510);
FORCEPROP 0 LASTPIN (-4075 5600) $PN 7
J 2
(-4085 5610);
DISPLAY 0.680851 (-4085 5610);
PAINT MONO (-4085 5610);
FORCEPROP 2 LAST PART_TYPE SMLF
J 0
(-3925 6000);
DISPLAY 0.680851 (-3925 6000);
FORCEPROP 2 LAST VALUE M24M02-DRMN6TP
J 0
(-3925 5950);
DISPLAY 0.680851 (-3925 5950);
FORCEPROP 1 LAST MATERIAL IC
J 0
(-3944 5707);
DISPLAY 0.723404 (-3944 5707);
PAINT GREEN (-3944 5707);
FORCEPROP 2 LAST CDS_LIB pure_quanta
J 0
(-3750 5575);
DISPLAY INVISIBLE (-3750 5575);
FORCEPROP 1 LAST CDS_LMAN_SYM_OUTLINE -175,125,175,-125
J 0
(-3750 5575);
DISPLAY 0.468085 (-3750 5575);
PAINT GREEN (-3750 5575);
DISPLAY INVISIBLE (-3750 5575);
FORCEPROP 1 LAST NEEDS_NO_SIZE TRUE
J 0
(-3575 5507);
DISPLAY 0.723404 (-3575 5507);
PAINT GREEN (-3575 5507);
DISPLAY INVISIBLE (-3575 5507);
FORCEPROP 1 LAST PATH I5
J 0
(-3575 5450);
DISPLAY 0.723404 (-3575 5450);
PAINT GREEN (-3575 5450);
DISPLAY INVISIBLE (-3575 5450);
FORCEPROP 1 LAST PART_NUMBER AKE33Z00600
J 0
(-3944 5801);
DISPLAY 0.723404 (-3944 5801);
PAINT GREEN (-3944 5801);
DISPLAY INVISIBLE (-3944 5801);
FORCEADD Q_RES..1
(-5175 5550);
FORCEPROP 1 LAST LOCATION R678
J 0
(-5425 5550);
DISPLAY 0.978723 (-5425 5550);
FORCEPROP 0 LAST $SEC 1
J 0
(-5300 5700);
DISPLAY 0.680851 (-5300 5700);
PAINT MONO (-5300 5700);
DISPLAY INVISIBLE (-5300 5700);
FORCEPROP 0 LAST CDS_SEC 1
J 0
(-5300 5700);
DISPLAY 0.680851 (-5300 5700);
DISPLAY INVISIBLE (-5300 5700);
FORCEPROP 1 LASTPIN (-5275 5550) $PN 1
J 0
(-5263 5562);
DISPLAY 0.787234 (-5263 5562);
PAINT MONO (-5263 5562);
FORCEPROP 1 LASTPIN (-5075 5550) $PN 2
J 0
(-5113 5562);
DISPLAY 0.787234 (-5113 5562);
PAINT MONO (-5113 5562);
FORCEPROP 1 LAST PACK_TYPE 0201LF
J 0
(-5175 5600);
DISPLAY 0.638298 (-5175 5600);
FORCEPROP 1 LAST WATTAGE 1/20W
J 2
(-5350 5600);
DISPLAY 0.638298 (-5350 5600);
FORCEPROP 1 LAST MATERIAL CHIP
J 0
(-5325 5600);
DISPLAY 0.638298 (-5325 5600);
FORCEPROP 1 LAST VALUE 33.2
J 2
(-5450 5650);
DISPLAY 0.638298 (-5450 5650);
FORCEPROP 1 LAST TOLERANCE 1%
J 0
(-5425 5650);
DISPLAY 0.638298 (-5425 5650);
FORCEPROP 2 LAST CDS_LIB pure_quanta
J 0
(-5175 5550);
DISPLAY INVISIBLE (-5175 5550);
FORCEPROP 1 LAST PATH I6
J 0
(-5225 5700);
DISPLAY 0.978723 (-5225 5700);
PAINT WHITE (-5225 5700);
DISPLAY INVISIBLE (-5225 5700);
FORCEPROP 1 LAST PART_NUMBER CS03321FE09
J 0
(-5300 5650);
DISPLAY 0.638298 (-5300 5650);
DISPLAY INVISIBLE (-5300 5650);
FORCEADD Q_RES..1
(-5175 5500);
FORCEPROP 1 LAST LOCATION R679
J 0
(-5425 5500);
DISPLAY 0.978723 (-5425 5500);
FORCEPROP 0 LAST $SEC 1
J 0
(-5425 5550);
DISPLAY 0.680851 (-5425 5550);
PAINT MONO (-5425 5550);
DISPLAY INVISIBLE (-5425 5550);
FORCEPROP 0 LAST CDS_SEC 1
J 0
(-5425 5550);
DISPLAY 0.680851 (-5425 5550);
DISPLAY INVISIBLE (-5425 5550);
FORCEPROP 1 LASTPIN (-5275 5500) $PN 1
J 0
(-5263 5512);
DISPLAY 0.787234 (-5263 5512);
PAINT MONO (-5263 5512);
FORCEPROP 1 LASTPIN (-5075 5500) $PN 2
J 0
(-5113 5512);
DISPLAY 0.787234 (-5113 5512);
PAINT MONO (-5113 5512);
FORCEPROP 1 LAST MATERIAL CHIP
J 0
(-5350 5550);
DISPLAY 0.787234 (-5350 5550);
DISPLAY INVISIBLE (-5350 5550);
FORCEPROP 1 LAST WATTAGE 1/20W
J 2
(-5350 5550);
DISPLAY 0.787234 (-5350 5550);
DISPLAY INVISIBLE (-5350 5550);
FORCEPROP 1 LAST PACK_TYPE 0201LF
J 0
(-5125 5550);
DISPLAY 0.787234 (-5125 5550);
DISPLAY INVISIBLE (-5125 5550);
FORCEPROP 2 LAST CDS_LIB pure_quanta
J 0
(-5175 5500);
DISPLAY INVISIBLE (-5175 5500);
FORCEPROP 1 LAST VALUE 33.2
J 2
(-5450 5600);
DISPLAY 0.787234 (-5450 5600);
DISPLAY INVISIBLE (-5450 5600);
FORCEPROP 1 LAST TOLERANCE 1%
J 0
(-5425 5600);
DISPLAY 0.787234 (-5425 5600);
DISPLAY INVISIBLE (-5425 5600);
FORCEPROP 1 LAST PATH I7
J 0
(-5225 5650);
DISPLAY 0.978723 (-5225 5650);
PAINT WHITE (-5225 5650);
DISPLAY INVISIBLE (-5225 5650);
FORCEPROP 1 LAST PART_NUMBER CS03321FE09
J 0
(-5300 5600);
DISPLAY 0.787234 (-5300 5600);
DISPLAY INVISIBLE (-5300 5600);
FORCEADD QUANTA_TITLE_BLOCK_C..1
(0 0);
FORCEPROP 0 LAST CDS_CON_LAST_MODIFIED Thu Sep 14 16:13:00 2023
J 0
(-1885 15);
DISPLAY INVISIBLE (-1885 15);
FORCEPROP 1 LAST CUSTOM_TXT_CDS <CON_LAST_MODIFIED>
J 0
(-1885 15);
DISPLAY 0.978723 (-1885 15);
FORCEPROP 2 LAST CUSTOM_TXT_CDS <XR_PAGE_TITLE>
J 0
(-7890 5250);
DISPLAY 0.638298 (-7890 5250);
PAINT PINK (-7890 5250);
DISPLAY INVISIBLE (-7890 5250);
FORCEPROP 1 LAST CUSTOM_TXT_CDS <NAME_2>
J 0
(-3175 50);
FORCEPROP 1 LAST CUSTOM_TXT_CDS <NAME_1>
J 0
(-3175 175);
FORCEPROP 1 LAST CUSTOM_TXT_CDS <Q_NUMBER>
J 0
(-1403 103);
DISPLAY 1.212766 (-1403 103);
FORCEPROP 1 LAST CUSTOM_TXT_CDS <Q_PROJ>
J 0
(-2382 102);
DISPLAY 1.212766 (-2382 102);
FORCEPROP 1 LAST CUSTOM_TXT_CDS <Q_REV>
J 0
(-184 103);
DISPLAY 1.212766 (-184 103);
FORCEPROP 1 LAST CUSTOM_TXT_CDS <CON_PAGE_NUM> OF <CON_TOTAL_PAGES>
J 0
(-446 18);
DISPLAY 0.978723 (-446 18);
FORCEPROP 1 LAST Q_TITLE RETIMER_CPU0_P1(7)
J 0
(-9366 26);
DISPLAY 2.446809 (-9366 26);
PAINT GREEN (-9366 26);
FORCEPROP 2 LAST PAGE_BORDER TRUE
J 0
(-7890 5250);
DISPLAY 0.638298 (-7890 5250);
PAINT PINK (-7890 5250);
DISPLAY INVISIBLE (-7890 5250);
FORCEPROP 1 LAST CDS_LMAN_SYM_OUTLINE -9475,6775,100,-125
J 0
(0 0);
DISPLAY 0.468085 (0 0);
PAINT GREEN (0 0);
DISPLAY INVISIBLE (0 0);
FORCEPROP 2 LAST CDS_LIB pure_quanta
J 0
(0 0);
DISPLAY INVISIBLE (0 0);
FORCEPROP 2 LAST CDS_XR_PAGE_TITLE CR-290 : @T6G_MB_LIB.T6G(SCH_1):PAGE290
J 0
(-7890 5250);
DISPLAY 0.638298 (-7890 5250);
PAINT PINK (-7890 5250);
DISPLAY INVISIBLE (-7890 5250);
FORCEPROP 1 LAST Q_DEPT BU9
J 1
(-3763 49);
DISPLAY 1.957447 (-3763 49);
PAINT GREEN (-3763 49);
DISPLAY INVISIBLE (-3763 49);
FORCEPROP 1 LAST COMMENT_BODY TRUE
J 0
(12 -13);
DISPLAY 0.978723 (12 -13);
PAINT GREEN (12 -13);
DISPLAY INVISIBLE (12 -13);
WIRE 16 -1 (-3425 5500)(-3225 5500);
WIRE 16 -1 (-3225 5500)(-3225 5350);
WIRE 16 -1 (-3075 5275)(-3075 5000);
WIRE 16 -1 (-4500 5975)(-4500 5850);
WIRE 16 -1 (-4075 5600)(-4175 5600);
WIRE 16 -1 (-5275 5500)(-6325 5500);
FORCEPROP 2 LAST SIG_NAME SMB_RT_CPU0_P1_ROM_R_SDA
J 0
(-6235 5510);
DISPLAY 0.680851 (-6235 5510);
WIRE 16 -1 (-4075 5500)(-5075 5500);
FORCEPROP 2 LAST SIG_NAME SMB_RT_CPU0_P1_ROM_SDA
J 0
(-4960 5510);
DISPLAY 0.680851 (-4960 5510);
FORCEPROP 2 LASTPROP $XRERR UNIQUE?
J 0
(-5200 5510);
DISPLAY 0.638298 (-5200 5510);
PAINT MONO (-5200 5510);
DISPLAY INVISIBLE (-5200 5510);
WIRE 16 -1 (-5275 5550)(-6350 5550);
FORCEPROP 2 LAST SIG_NAME SMB_RT_CPU0_P1_ROM_R_SCL
J 0
(-6235 5560);
DISPLAY 0.680851 (-6235 5560);
WIRE 16 -1 (-4075 5550)(-5075 5550);
FORCEPROP 2 LAST SIG_NAME SMB_RT_CPU0_P1_ROM_SCL
J 0
(-4960 5560);
DISPLAY 0.680851 (-4960 5560);
FORCEPROP 2 LASTPROP $XRERR UNIQUE?
J 0
(-5200 5560);
DISPLAY 0.638298 (-5200 5560);
PAINT MONO (-5200 5560);
DISPLAY INVISIBLE (-5200 5560);
WIRE 16 -1 (-4500 6175)(-4500 6300);
WIRE 16 -1 (-4500 6300)(-4200 6300);
WIRE 16 -1 (-4200 6375)(-4200 6300);
WIRE 16 -1 (-4200 6300)(-4200 5650);
WIRE 16 -1 (-4200 5650)(-4075 5650);
WIRE 16 -1 (-3075 5550)(-3075 5475);
WIRE 16 -1 (-3425 5550)(-3075 5550);
FORCEPROP 2 LAST SIG_NAME U15_E2
J 0
(-3285 5560);
DISPLAY 0.680851 (-3285 5560);
FORCEPROP 2 LASTPROP $XRERR UNIQUE?
J 0
(-3525 5560);
DISPLAY 0.638298 (-3525 5560);
PAINT MONO (-3525 5560);
DISPLAY INVISIBLE (-3525 5560);
DOT 1 (-4200 6300);
FORCENOTE
RETIMER EEPRO ADDRESS: 0XA0 (8 BIT) / 0X50 (7 BIT)
(-7475 5125) 0;
DISPLAY LEFT (-7475 5125);
DISPLAY 1.595745 (-7475 5125);
QUIT
